# S9S_MB_2U (Grand Teton) — schematic netlist excerpt (pin names and nets, part order shuffled) for the footprints in the layout excerpt that follows; sources: Cadence DE-HDL packaged netlist, KiCad conversion of 03242023_DA0F0TMBIJ0_F0T_Motherboard_J_brd_V01_OCP.brd

R3060  Q_RES  33.2 1% CHIP  pkg 0402LF  page 241 : A = SMB_SML1_PMBUS_3V3AUX_PCH_SCL ; B = SMB_PMBUS_SML1_ME_SCL
R3184  Q_RES  4.7K 1% CHIP  pkg 0402LF  page 161 : A = P3V3_AUX ; B = OCP_V3_2_WAKE_BUFF_N

(kicad_pcb
	(version 20260206)
	(generator "pcbnew")
	(generator_version "10.0")
	(general
		(thickness 1.6)
		(legacy_teardrops no)
	)
	(paper "A4")
	(title_block
		(title "03242023_DA0F0TMBIJ0_F0T_Motherboard_J_brd_V01_OCP.brd")
		(comment 1 "Grand Teton / footprints 1108-1109 of 6105")
	)
	(layers
		(0 "F.Cu" signal "TOP")
		(4 "In1.Cu" signal "GND")
		(6 "In2.Cu" signal "IN1")
		(8 "In3.Cu" signal "GND1")
		(10 "In4.Cu" signal "IN2")
		(12 "In5.Cu" signal "GND2")
		(14 "In6.Cu" signal "IN3")
		(16 "In7.Cu" signal "GND3")
		(18 "In8.Cu" signal "VCC")
		(20 "In9.Cu" signal "VCC1")
		(22 "In10.Cu" signal "GND4")
		(24 "In11.Cu" signal "IN4")
		(26 "In12.Cu" signal "GND5")
		(28 "In13.Cu" signal "IN5")
		(30 "In14.Cu" signal "GND6")
		(32 "In15.Cu" signal "IN6")
		(34 "In16.Cu" signal "GND7")
		(2 "B.Cu" signal "BOTTOM")
		(9 "F.Adhes" user "F.Adhesive")
		(11 "B.Adhes" user "B.Adhesive")
		(13 "F.Paste" user "Package Geometry/Pastemask Top")
		(15 "B.Paste" user "Package Geometry/Pastemask Bottom")
		(5 "F.SilkS" user "Ref Des/Silkscreen Top")
		(7 "B.SilkS" user "Ref Des/Silkscreen Bottom")
		(1 "F.Mask" user "Board Geometry/Soldermask Top")
		(3 "B.Mask" user "Board Geometry/Soldermask Bottom")
		(17 "Dwgs.User" user "User.Drawings")
		(19 "Cmts.User" user "User.Comments")
		(21 "Eco1.User" user "User.Eco1")
		(23 "Eco2.User" user "User.Eco2")
		(25 "Edge.Cuts" user "Board Geometry/Outline")
		(27 "Margin" user)
		(31 "F.CrtYd" user "Package Geometry/Place Bound Top")
		(29 "B.CrtYd" user "Package Geometry/Place Bound Bottom")
		(35 "F.Fab" user "Ref Des/Assembly Top")
		(33 "B.Fab" user "Ref Des/Assembly Bottom")
	)
	(footprint ""
		(layer "F.Cu")
		(at 274.495006 -19.952462)
		(property "Reference" "R3184"
			(at 0 0 0)
			(layer "F.SilkS")
			(hide yes)
			(effects
				(font
					(size 1.27 1.27)
				)
			)
		)
		(property "Value" ""
			(at 0 0 0)
			(layer "F.Fab")
			(effects
				(font
					(size 1.27 1.27)
				)
			)
		)
		(duplicate_pad_numbers_are_jumpers no)
		(fp_line
			(start -0.7874 -0.4064)
			(end 0.7874 -0.4064)
			(stroke
				(width 0.1524)
				(type default)
			)
			(layer "F.SilkS")
		)
		(fp_line
			(start -0.7874 0.4064)
			(end -0.7874 -0.4064)
			(stroke
				(width 0.1524)
				(type default)
			)
			(layer "F.SilkS")
		)
		(fp_line
			(start 0.7874 -0.4064)
			(end 0.7874 0.4064)
			(stroke
				(width 0.1524)
				(type default)
			)
			(layer "F.SilkS")
		)
		(fp_line
			(start 0.7874 0.4064)
			(end -0.7874 0.4064)
			(stroke
				(width 0.1524)
				(type default)
			)
			(layer "F.SilkS")
		)
		(fp_line
			(start -0.67945 -0.305054)
			(end -0.12065 -0.305054)
			(stroke
				(width 0.1)
				(type default)
			)
			(layer "F.Fab")
		)
		(fp_line
			(start -0.67945 0.3048)
			(end -0.67945 -0.305054)
			(stroke
				(width 0.1)
				(type default)
			)
			(layer "F.Fab")
		)
		(fp_line
			(start -0.12065 -0.305054)
			(end -0.12065 -0.2794)
			(stroke
				(width 0.1)
				(type default)
			)
			(layer "F.Fab")
		)
		(fp_line
			(start -0.12065 -0.2794)
			(end 0.12065 -0.2794)
			(stroke
				(width 0.1)
				(type default)
			)
			(layer "F.Fab")
		)
		(fp_line
			(start -0.12065 0.2794)
			(end -0.12065 0.3048)
			(stroke
				(width 0.1)
				(type default)
			)
			(layer "F.Fab")
		)
		(fp_line
			(start -0.12065 0.3048)
			(end -0.67945 0.3048)
			(stroke
				(width 0.1)
				(type default)
			)
			(layer "F.Fab")
		)
		(fp_line
			(start 0.120396 0.2794)
			(end -0.12065 0.2794)
			(stroke
				(width 0.1)
				(type default)
			)
			(layer "F.Fab")
		)
		(fp_line
			(start 0.120396 0.3048)
			(end 0.120396 0.2794)
			(stroke
				(width 0.1)
				(type default)
			)
			(layer "F.Fab")
		)
		(fp_line
			(start 0.12065 -0.3048)
			(end 0.67945 -0.3048)
			(stroke
				(width 0.1)
				(type default)
			)
			(layer "F.Fab")
		)
		(fp_line
			(start 0.12065 -0.2794)
			(end 0.12065 -0.3048)
			(stroke
				(width 0.1)
				(type default)
			)
			(layer "F.Fab")
		)
		(fp_line
			(start 0.67945 -0.3048)
			(end 0.67945 0.3048)
			(stroke
				(width 0.1)
				(type default)
			)
			(layer "F.Fab")
		)
		(fp_line
			(start 0.67945 0.3048)
			(end 0.120396 0.3048)
			(stroke
				(width 0.1)
				(type default)
			)
			(layer "F.Fab")
		)
		(pad "1" smd circle
			(at -0.40005 0)
			(size 0 0)
			(layers "F.Cu" "F.Mask" "F.Paste")
			(net "P3V3_AUX")
		)
		(pad "2" smd circle
			(at 0.40005 0)
			(size 0 0)
			(layers "F.Cu" "F.Mask" "F.Paste")
			(net "OCP_V3_2_WAKE_BUFF_N")
		)
	)
	(footprint ""
		(layer "F.Cu")
		(at 9.58088 -56.982868)
		(property "Reference" "R3060"
			(at 0 0 0)
			(layer "F.SilkS")
			(hide yes)
			(effects
				(font
					(size 1.27 1.27)
				)
			)
		)
		(property "Value" ""
			(at 0 0 0)
			(layer "F.Fab")
			(effects
				(font
					(size 1.27 1.27)
				)
			)
		)
		(duplicate_pad_numbers_are_jumpers no)
		(fp_line
			(start -0.7874 -0.4064)
			(end 0.7874 -0.4064)
			(stroke
				(width 0.1524)
				(type default)
			)
			(layer "F.SilkS")
		)
		(fp_line
			(start -0.7874 0.4064)
			(end -0.7874 -0.4064)
			(stroke
				(width 0.1524)
				(type default)
			)
			(layer "F.SilkS")
		)
		(fp_line
			(start 0.7874 -0.4064)
			(end 0.7874 0.4064)
			(stroke
				(width 0.1524)
				(type default)
			)
			(layer "F.SilkS")
		)
		(fp_line
			(start 0.7874 0.4064)
			(end -0.7874 0.4064)
			(stroke
				(width 0.1524)
				(type default)
			)
			(layer "F.SilkS")
		)
		(fp_line
			(start -0.67945 -0.305054)
			(end -0.12065 -0.305054)
			(stroke
				(width 0.1)
				(type default)
			)
			(layer "F.Fab")
		)
		(fp_line
			(start -0.67945 0.3048)
			(end -0.67945 -0.305054)
			(stroke
				(width 0.1)
				(type default)
			)
			(layer "F.Fab")
		)
		(fp_line
			(start -0.12065 -0.305054)
			(end -0.12065 -0.2794)
			(stroke
				(width 0.1)
				(type default)
			)
			(layer "F.Fab")
		)
		(fp_line
			(start -0.12065 -0.2794)
			(end 0.12065 -0.2794)
			(stroke
				(width 0.1)
				(type default)
			)
			(layer "F.Fab")
		)
		(fp_line
			(start -0.12065 0.2794)
			(end -0.12065 0.3048)
			(stroke
				(width 0.1)
				(type default)
			)
			(layer "F.Fab")
		)
		(fp_line
			(start -0.12065 0.3048)
			(end -0.67945 0.3048)
			(stroke
				(width 0.1)
				(type default)
			)
			(layer "F.Fab")
		)
		(fp_line
			(start 0.120396 0.2794)
			(end -0.12065 0.2794)
			(stroke
				(width 0.1)
				(type default)
			)
			(layer "F.Fab")
		)
		(fp_line
			(start 0.120396 0.3048)
			(end 0.120396 0.2794)
			(stroke
				(width 0.1)
				(type default)
			)
			(layer "F.Fab")
		)
		(fp_line
			(start 0.12065 -0.3048)
			(end 0.67945 -0.3048)
			(stroke
				(width 0.1)
				(type default)
			)
			(layer "F.Fab")
		)
		(fp_line
			(start 0.12065 -0.2794)
			(end 0.12065 -0.3048)
			(stroke
				(width 0.1)
				(type default)
			)
			(layer "F.Fab")
		)
		(fp_line
			(start 0.67945 -0.3048)
			(end 0.67945 0.3048)
			(stroke
				(width 0.1)
				(type default)
			)
			(layer "F.Fab")
		)
		(fp_line
			(start 0.67945 0.3048)
			(end 0.120396 0.3048)
			(stroke
				(width 0.1)
				(type default)
			)
			(layer "F.Fab")
		)
		(pad "1" smd circle
			(at -0.40005 0)
			(size 0 0)
			(layers "F.Cu" "F.Mask" "F.Paste")
			(net "SMB_SML1_PMBUS_3V3AUX_PCH_SCL")
		)
		(pad "2" smd circle
			(at 0.40005 0)
			(size 0 0)
			(layers "F.Cu" "F.Mask" "F.Paste")
			(net "SMB_PMBUS_SML1_ME_SCL")
		)
	)
)
